# S9S_MB_2U (Grand Teton) — schematic netlist excerpt (pin names and nets, part order shuffled) for the footprints in the layout excerpt that follows; sources: Cadence DE-HDL packaged netlist, KiCad conversion of 03242023_DA0F0TMBIJ0_F0T_Motherboard_J_brd_V01_OCP.brd

C1791  Q_CAP_DIFFBUS  DIFF BUS_0.22UF 6.3V 20% X6S  pkg C0201  page 178 : \1\ = DMI_CPU0_PCH_TX_C_DP<7> ; \2\ = DMI_CPU0_PCH_TX_DP<7>
C902  Q_CAP_DIFFBUS  DIFF BUS_0.22UF 6.3V 20% X6S  pkg C0201  page 173 : \1\ = P5E_CPU0_PE0_TX_C_DN<15> ; \2\ = P5E_CPU0_PE0_TX_DN<15>
R4575  Q_RES  0 5% EMPTY  pkg 0402LF  page 146 : A = GPU_3V3IO_RSVD0_FFU ; B = GPU_3V3IO_RSVD0_FFU_ISO

(kicad_pcb
	(version 20260206)
	(generator "pcbnew")
	(generator_version "10.0")
	(general
		(thickness 1.6)
		(legacy_teardrops no)
	)
	(paper "A4")
	(title_block
		(title "03242023_DA0F0TMBIJ0_F0T_Motherboard_J_brd_V01_OCP.brd")
		(comment 1 "Grand Teton / footprints 2466-2468 of 6105")
	)
	(layers
		(0 "F.Cu" signal "TOP")
		(4 "In1.Cu" signal "GND")
		(6 "In2.Cu" signal "IN1")
		(8 "In3.Cu" signal "GND1")
		(10 "In4.Cu" signal "IN2")
		(12 "In5.Cu" signal "GND2")
		(14 "In6.Cu" signal "IN3")
		(16 "In7.Cu" signal "GND3")
		(18 "In8.Cu" signal "VCC")
		(20 "In9.Cu" signal "VCC1")
		(22 "In10.Cu" signal "GND4")
		(24 "In11.Cu" signal "IN4")
		(26 "In12.Cu" signal "GND5")
		(28 "In13.Cu" signal "IN5")
		(30 "In14.Cu" signal "GND6")
		(32 "In15.Cu" signal "IN6")
		(34 "In16.Cu" signal "GND7")
		(2 "B.Cu" signal "BOTTOM")
		(9 "F.Adhes" user "F.Adhesive")
		(11 "B.Adhes" user "B.Adhesive")
		(13 "F.Paste" user "Package Geometry/Pastemask Top")
		(15 "B.Paste" user "Package Geometry/Pastemask Bottom")
		(5 "F.SilkS" user "Ref Des/Silkscreen Top")
		(7 "B.SilkS" user "Ref Des/Silkscreen Bottom")
		(1 "F.Mask" user "Board Geometry/Soldermask Top")
		(3 "B.Mask" user "Board Geometry/Soldermask Bottom")
		(17 "Dwgs.User" user "User.Drawings")
		(19 "Cmts.User" user "User.Comments")
		(21 "Eco1.User" user "User.Eco1")
		(23 "Eco2.User" user "User.Eco2")
		(25 "Edge.Cuts" user "Board Geometry/Outline")
		(27 "Margin" user)
		(31 "F.CrtYd" user "Package Geometry/Place Bound Top")
		(29 "B.CrtYd" user "Package Geometry/Place Bound Bottom")
		(35 "F.Fab" user "Ref Des/Assembly Top")
		(33 "B.Fab" user "Ref Des/Assembly Bottom")
	)
	(footprint ""
		(layer "F.Cu")
		(at 303.52873 -417.29914)
		(property "Reference" "R4575"
			(at 0 0 0)
			(layer "F.SilkS")
			(hide yes)
			(effects
				(font
					(size 1.27 1.27)
				)
			)
		)
		(property "Value" ""
			(at 0 0 0)
			(layer "F.Fab")
			(effects
				(font
					(size 1.27 1.27)
				)
			)
		)
		(duplicate_pad_numbers_are_jumpers no)
		(fp_line
			(start -0.7874 -0.4064)
			(end 0.7874 -0.4064)
			(stroke
				(width 0.1524)
				(type default)
			)
			(layer "F.SilkS")
		)
		(fp_line
			(start -0.7874 0.4064)
			(end -0.7874 -0.4064)
			(stroke
				(width 0.1524)
				(type default)
			)
			(layer "F.SilkS")
		)
		(fp_line
			(start 0.7874 -0.4064)
			(end 0.7874 0.4064)
			(stroke
				(width 0.1524)
				(type default)
			)
			(layer "F.SilkS")
		)
		(fp_line
			(start 0.7874 0.4064)
			(end -0.7874 0.4064)
			(stroke
				(width 0.1524)
				(type default)
			)
			(layer "F.SilkS")
		)
		(fp_line
			(start -0.67945 -0.305054)
			(end -0.12065 -0.305054)
			(stroke
				(width 0.1)
				(type default)
			)
			(layer "F.Fab")
		)
		(fp_line
			(start -0.67945 0.3048)
			(end -0.67945 -0.305054)
			(stroke
				(width 0.1)
				(type default)
			)
			(layer "F.Fab")
		)
		(fp_line
			(start -0.12065 -0.305054)
			(end -0.12065 -0.2794)
			(stroke
				(width 0.1)
				(type default)
			)
			(layer "F.Fab")
		)
		(fp_line
			(start -0.12065 -0.2794)
			(end 0.12065 -0.2794)
			(stroke
				(width 0.1)
				(type default)
			)
			(layer "F.Fab")
		)
		(fp_line
			(start -0.12065 0.2794)
			(end -0.12065 0.3048)
			(stroke
				(width 0.1)
				(type default)
			)
			(layer "F.Fab")
		)
		(fp_line
			(start -0.12065 0.3048)
			(end -0.67945 0.3048)
			(stroke
				(width 0.1)
				(type default)
			)
			(layer "F.Fab")
		)
		(fp_line
			(start 0.120396 0.2794)
			(end -0.12065 0.2794)
			(stroke
				(width 0.1)
				(type default)
			)
			(layer "F.Fab")
		)
		(fp_line
			(start 0.120396 0.3048)
			(end 0.120396 0.2794)
			(stroke
				(width 0.1)
				(type default)
			)
			(layer "F.Fab")
		)
		(fp_line
			(start 0.12065 -0.3048)
			(end 0.67945 -0.3048)
			(stroke
				(width 0.1)
				(type default)
			)
			(layer "F.Fab")
		)
		(fp_line
			(start 0.12065 -0.2794)
			(end 0.12065 -0.3048)
			(stroke
				(width 0.1)
				(type default)
			)
			(layer "F.Fab")
		)
		(fp_line
			(start 0.67945 -0.3048)
			(end 0.67945 0.3048)
			(stroke
				(width 0.1)
				(type default)
			)
			(layer "F.Fab")
		)
		(fp_line
			(start 0.67945 0.3048)
			(end 0.120396 0.3048)
			(stroke
				(width 0.1)
				(type default)
			)
			(layer "F.Fab")
		)
		(pad "1" smd circle
			(at -0.40005 0)
			(size 0 0)
			(layers "F.Cu" "F.Mask" "F.Paste")
			(net "GPU_3V3IO_RSVD0_FFU")
		)
		(pad "2" smd circle
			(at 0.40005 0)
			(size 0 0)
			(layers "F.Cu" "F.Mask" "F.Paste")
			(net "GPU_3V3IO_RSVD0_FFU_ISO")
		)
	)
	(footprint ""
		(layer "F.Cu")
		(at 350.691196 -61.506354)
		(property "Reference" "C1791"
			(at 0 0 0)
			(layer "F.SilkS")
			(hide yes)
			(effects
				(font
					(size 1.27 1.27)
				)
			)
		)
		(property "Value" ""
			(at 0 0 0)
			(layer "F.Fab")
			(effects
				(font
					(size 1.27 1.27)
				)
			)
		)
		(duplicate_pad_numbers_are_jumpers no)
		(fp_line
			(start -0.299974 -0.150114)
			(end 0.299974 -0.150114)
			(stroke
				(width 0.1)
				(type default)
			)
			(layer "F.Fab")
		)
		(fp_line
			(start -0.299974 0.150114)
			(end -0.299974 -0.150114)
			(stroke
				(width 0.1)
				(type default)
			)
			(layer "F.Fab")
		)
		(fp_line
			(start 0.299974 -0.150114)
			(end 0.299974 0.150114)
			(stroke
				(width 0.1)
				(type default)
			)
			(layer "F.Fab")
		)
		(fp_line
			(start 0.299974 0.150114)
			(end -0.299974 0.150114)
			(stroke
				(width 0.1)
				(type default)
			)
			(layer "F.Fab")
		)
		(pad "1" smd rect
			(at -0.2667 0)
			(size 0.3048 0.381)
			(layers "F.Cu" "F.Mask" "F.Paste")
			(net "DMI_CPU0_PCH_TX_C_DP<7>")
		)
		(pad "2" smd rect
			(at 0.2667 0)
			(size 0.3048 0.381)
			(layers "F.Cu" "F.Mask" "F.Paste")
			(net "DMI_CPU0_PCH_TX_DP<7>")
		)
		(zone
			(layer "In1.Cu")
			(hatch none 0.5)
			(connect_pads
				(clearance 0)
			)
			(min_thickness 0.25)
			(keepout
				(tracks not_allowed)
				(vias allowed)
				(pads allowed)
				(copperpour not_allowed)
				(footprints allowed)
			)
			(placement
				(enabled no)
				(sheetname "")
			)
			(fill
				(thermal_gap 0.5)
				(thermal_bridge_width 0.5)
				(island_removal_mode 0)
			)
			(polygon
				(pts
					(arc
						(start 350.297496 -61.265054)
						(mid 350.243614 -61.287372)
						(end 350.221296 -61.341254)
					)
					(arc
						(start 350.221296 -61.671454)
						(mid 350.243614 -61.725336)
						(end 350.297496 -61.747654)
					)
					(arc
						(start 350.551496 -61.747654)
						(mid 350.605378 -61.725336)
						(end 350.627696 -61.671454)
					)
					(arc
						(start 350.627696 -61.341254)
						(mid 350.605378 -61.287372)
						(end 350.551496 -61.265054)
					)
				)
			)
		)
		(zone
			(layer "In1.Cu")
			(hatch none 0.5)
			(connect_pads
				(clearance 0)
			)
			(min_thickness 0.25)
			(keepout
				(tracks not_allowed)
				(vias allowed)
				(pads allowed)
				(copperpour not_allowed)
				(footprints allowed)
			)
			(placement
				(enabled no)
				(sheetname "")
			)
			(fill
				(thermal_gap 0.5)
				(thermal_bridge_width 0.5)
				(island_removal_mode 0)
			)
			(polygon
				(pts
					(arc
						(start 350.830896 -61.265054)
						(mid 350.777014 -61.287372)
						(end 350.754696 -61.341254)
					)
					(arc
						(start 350.754696 -61.671454)
						(mid 350.777014 -61.725336)
						(end 350.830896 -61.747654)
					)
					(arc
						(start 351.084896 -61.747654)
						(mid 351.138778 -61.725336)
						(end 351.161096 -61.671454)
					)
					(arc
						(start 351.161096 -61.341254)
						(mid 351.138778 -61.287372)
						(end 351.084896 -61.265054)
					)
				)
			)
		)
	)
	(footprint ""
		(layer "F.Cu")
		(at 305.300888 -408.517344 -90)
		(property "Reference" "C902"
			(at 0 0 270)
			(layer "F.SilkS")
			(hide yes)
			(effects
				(font
					(size 1.27 1.27)
				)
			)
		)
		(property "Value" ""
			(at 0 0 270)
			(layer "F.Fab")
			(effects
				(font
					(size 1.27 1.27)
				)
			)
		)
		(duplicate_pad_numbers_are_jumpers no)
		(fp_line
			(start -0.299974 0.150114)
			(end -0.299974 -0.150114)
			(stroke
				(width 0.1)
				(type default)
			)
			(layer "F.Fab")
		)
		(fp_line
			(start 0.299974 0.150114)
			(end -0.299974 0.150114)
			(stroke
				(width 0.1)
				(type default)
			)
			(layer "F.Fab")
		)
		(fp_line
			(start -0.299974 -0.150114)
			(end 0.299974 -0.150114)
			(stroke
				(width 0.1)
				(type default)
			)
			(layer "F.Fab")
		)
		(fp_line
			(start 0.299974 -0.150114)
			(end 0.299974 0.150114)
			(stroke
				(width 0.1)
				(type default)
			)
			(layer "F.Fab")
		)
		(pad "1" smd rect
			(at -0.2667 0 270)
			(size 0.3048 0.381)
			(layers "F.Cu" "F.Mask" "F.Paste")
			(net "P5E_CPU0_PE0_TX_C_DN<15>")
		)
		(pad "2" smd rect
			(at 0.2667 0 270)
			(size 0.3048 0.381)
			(layers "F.Cu" "F.Mask" "F.Paste")
			(net "P5E_CPU0_PE0_TX_DN<15>")
		)
	)
)
